(kicad_pcb
	(version 20260206)
	(generator "pcbnew")
	(generator_version "10.0")
	(general
		(thickness 1.6)
		(legacy_teardrops no)
	)
	(paper "A4")
	(title_block
		(title "04192023_DAF0TMB3IC0_F0TG_MB_C_brd_V02_OCP.brd")
		(comment 1 "Grand Teton / footprints 3274-3279 of 8354")
	)
	(layers
		(0 "F.Cu" signal "TOP")
		(4 "In1.Cu" signal "GND")
		(6 "In2.Cu" signal "IN1")
		(8 "In3.Cu" signal "GND1")
		(10 "In4.Cu" signal "IN2")
		(12 "In5.Cu" signal "GND2")
		(14 "In6.Cu" signal "IN3")
		(16 "In7.Cu" signal "GND3")
		(18 "In8.Cu" signal "VCC")
		(20 "In9.Cu" signal "VCC1")
		(22 "In10.Cu" signal "GND4")
		(24 "In11.Cu" signal "IN4")
		(26 "In12.Cu" signal "GND5")
		(28 "In13.Cu" signal "IN5")
		(30 "In14.Cu" signal "GND6")
		(32 "In15.Cu" signal "IN6")
		(34 "In16.Cu" signal "GND7")
		(2 "B.Cu" signal "BOTTOM")
		(9 "F.Adhes" user "F.Adhesive")
		(11 "B.Adhes" user "B.Adhesive")
		(13 "F.Paste" user "Package Geometry/Pastemask Top")
		(15 "B.Paste" user "Package Geometry/Pastemask Bottom")
		(5 "F.SilkS" user "Ref Des/Silkscreen Top")
		(7 "B.SilkS" user "Ref Des/Silkscreen Bottom")
		(1 "F.Mask" user "Board Geometry/Soldermask Top")
		(3 "B.Mask" user "Board Geometry/Soldermask Bottom")
		(17 "Dwgs.User" user "User.Drawings")
		(19 "Cmts.User" user "User.Comments")
		(21 "Eco1.User" user "User.Eco1")
		(23 "Eco2.User" user "User.Eco2")
		(25 "Edge.Cuts" user "Board Geometry/Outline")
		(27 "Margin" user)
		(31 "F.CrtYd" user "Package Geometry/Place Bound Top")
		(29 "B.CrtYd" user "Package Geometry/Place Bound Bottom")
		(35 "F.Fab" user "Ref Des/Assembly Top")
		(33 "B.Fab" user "Ref Des/Assembly Bottom")
	)
	(footprint ""
		(layer "F.Cu")
		(at 457.684632 -107.018836)
		(property "Reference" "U211"
			(at -1.4732 -1.768348 0)
			(unlocked yes)
			(layer "F.SilkS")
			(effects
				(font
					(size 0.7874 0.5842)
					(thickness 0.1524)
				)
				(justify left)
			)
		)
		(property "Value" ""
			(at 0 0 0)
			(layer "F.Fab")
			(effects
				(font
					(size 1.27 1.27)
				)
			)
		)
		(duplicate_pad_numbers_are_jumpers no)
		(fp_line
			(start -1.38176 -1.100074)
			(end -1.38176 1.100074)
			(stroke
				(width 0.1524)
				(type default)
			)
			(layer "F.SilkS")
		)
		(fp_line
			(start -1.38176 1.100074)
			(end 1.38176 1.100074)
			(stroke
				(width 0.1524)
				(type default)
			)
			(layer "F.SilkS")
		)
		(fp_line
			(start -0.592074 -1.100074)
			(end -1.38176 -1.100074)
			(stroke
				(width 0.1524)
				(type default)
			)
			(layer "F.SilkS")
		)
		(fp_line
			(start 0 -0.508)
			(end -0.592074 -1.100074)
			(stroke
				(width 0.1524)
				(type default)
			)
			(layer "F.SilkS")
		)
		(fp_line
			(start 0.592074 -1.100074)
			(end 0 -0.508)
			(stroke
				(width 0.1524)
				(type default)
			)
			(layer "F.SilkS")
		)
		(fp_line
			(start 1.38176 -1.100074)
			(end 0.592074 -1.100074)
			(stroke
				(width 0.1524)
				(type default)
			)
			(layer "F.SilkS")
		)
		(fp_line
			(start 1.38176 1.100074)
			(end 1.38176 -1.100074)
			(stroke
				(width 0.1524)
				(type default)
			)
			(layer "F.SilkS")
		)
		(fp_poly
			(pts
				(xy -1.9431 -0.429768) (xy -1.9431 -0.870204) (xy -1.50241 -0.649986)
			)
			(stroke
				(width 0)
				(type default)
			)
			(fill yes)
			(layer "F.SilkS")
		)
		(fp_line
			(start -0.674878 -1.100074)
			(end -0.674878 1.100074)
			(stroke
				(width 0.1)
				(type default)
			)
			(layer "F.Fab")
		)
		(fp_line
			(start -0.674878 1.100074)
			(end 0.674878 1.100074)
			(stroke
				(width 0.1)
				(type default)
			)
			(layer "F.Fab")
		)
		(fp_line
			(start 0.674878 -1.100074)
			(end -0.674878 -1.100074)
			(stroke
				(width 0.1)
				(type default)
			)
			(layer "F.Fab")
		)
		(fp_line
			(start 0.674878 1.100074)
			(end 0.674878 -1.100074)
			(stroke
				(width 0.1)
				(type default)
			)
			(layer "F.Fab")
		)
		(fp_poly
			(pts
				(xy -1.9431 -0.870204) (xy -1.50241 -0.649986) (xy -1.9431 -0.429768)
			)
			(stroke
				(width 0)
				(type default)
			)
			(fill yes)
			(layer "F.Fab")
		)
		(pad "1" smd rect
			(at -0.94996 -0.649986 270)
			(size 0.4318 0.6096)
			(layers "F.Cu" "F.Mask" "F.Paste")
			(net "OCP_SFF_PRSNT0_R_N")
		)
		(pad "2" smd rect
			(at -0.94996 0 270)
			(size 0.4318 0.6096)
			(layers "F.Cu" "F.Mask" "F.Paste")
			(net "GND")
		)
		(pad "3" smd rect
			(at -0.94996 0.649986 270)
			(size 0.4318 0.6096)
			(layers "F.Cu" "F.Mask" "F.Paste")
			(net "OCP_SFF_PRSNT1_R_N")
		)
		(pad "4" smd rect
			(at 0.94996 0.649986 270)
			(size 0.4318 0.6096)
			(layers "F.Cu" "F.Mask" "F.Paste")
			(net "HP_LVC3_OCP_V3_1_PRSNT2_N_R")
		)
		(pad "5" smd rect
			(at 0.94996 0 270)
			(size 0.4318 0.6096)
			(layers "F.Cu" "F.Mask" "F.Paste")
			(net "P3V3_AUX")
		)
		(pad "6" smd rect
			(at 0.94996 -0.649986 270)
			(size 0.4318 0.6096)
			(layers "F.Cu" "F.Mask" "F.Paste")
			(net "HP_LVC3_OCP_V3_1_PRSNT2_N_R")
		)
	)
	(footprint ""
		(layer "F.Cu")
		(at 10.066782 -412.215584)
		(property "Reference" "PR6533"
			(at 0 0 0)
			(layer "F.SilkS")
			(hide yes)
			(effects
				(font
					(size 1.27 1.27)
				)
			)
		)
		(property "Value" ""
			(at 0 0 0)
			(layer "F.Fab")
			(effects
				(font
					(size 1.27 1.27)
				)
			)
		)
		(duplicate_pad_numbers_are_jumpers no)
		(fp_line
			(start -0.7874 -0.4064)
			(end 0.7874 -0.4064)
			(stroke
				(width 0.1524)
				(type default)
			)
			(layer "F.SilkS")
		)
		(fp_line
			(start -0.7874 0.4064)
			(end -0.7874 -0.4064)
			(stroke
				(width 0.1524)
				(type default)
			)
			(layer "F.SilkS")
		)
		(fp_line
			(start 0.7874 -0.4064)
			(end 0.7874 0.4064)
			(stroke
				(width 0.1524)
				(type default)
			)
			(layer "F.SilkS")
		)
		(fp_line
			(start 0.7874 0.4064)
			(end -0.7874 0.4064)
			(stroke
				(width 0.1524)
				(type default)
			)
			(layer "F.SilkS")
		)
		(fp_line
			(start -0.67945 -0.305054)
			(end -0.12065 -0.305054)
			(stroke
				(width 0.1)
				(type default)
			)
			(layer "F.Fab")
		)
		(fp_line
			(start -0.67945 0.3048)
			(end -0.67945 -0.305054)
			(stroke
				(width 0.1)
				(type default)
			)
			(layer "F.Fab")
		)
		(fp_line
			(start -0.12065 -0.305054)
			(end -0.12065 -0.2794)
			(stroke
				(width 0.1)
				(type default)
			)
			(layer "F.Fab")
		)
		(fp_line
			(start -0.12065 -0.2794)
			(end 0.12065 -0.2794)
			(stroke
				(width 0.1)
				(type default)
			)
			(layer "F.Fab")
		)
		(fp_line
			(start -0.12065 0.2794)
			(end -0.12065 0.3048)
			(stroke
				(width 0.1)
				(type default)
			)
			(layer "F.Fab")
		)
		(fp_line
			(start -0.12065 0.3048)
			(end -0.67945 0.3048)
			(stroke
				(width 0.1)
				(type default)
			)
			(layer "F.Fab")
		)
		(fp_line
			(start 0.120396 0.2794)
			(end -0.12065 0.2794)
			(stroke
				(width 0.1)
				(type default)
			)
			(layer "F.Fab")
		)
		(fp_line
			(start 0.120396 0.3048)
			(end 0.120396 0.2794)
			(stroke
				(width 0.1)
				(type default)
			)
			(layer "F.Fab")
		)
		(fp_line
			(start 0.12065 -0.3048)
			(end 0.67945 -0.3048)
			(stroke
				(width 0.1)
				(type default)
			)
			(layer "F.Fab")
		)
		(fp_line
			(start 0.12065 -0.2794)
			(end 0.12065 -0.3048)
			(stroke
				(width 0.1)
				(type default)
			)
			(layer "F.Fab")
		)
		(fp_line
			(start 0.67945 -0.3048)
			(end 0.67945 0.3048)
			(stroke
				(width 0.1)
				(type default)
			)
			(layer "F.Fab")
		)
		(fp_line
			(start 0.67945 0.3048)
			(end 0.120396 0.3048)
			(stroke
				(width 0.1)
				(type default)
			)
			(layer "F.Fab")
		)
		(pad "1" smd circle
			(at -0.40005 0)
			(size 0 0)
			(layers "F.Cu" "F.Mask" "F.Paste")
			(net "GND")
		)
		(pad "2" smd circle
			(at 0.40005 0)
			(size 0 0)
			(layers "F.Cu" "F.Mask" "F.Paste")
			(net "P0V9_RETIMER_CPU1_ADDR")
		)
	)
	(footprint ""
		(layer "F.Cu")
		(at 178.71694 -403.484842 180)
		(property "Reference" "PR2149"
			(at 0 0 180)
			(layer "F.SilkS")
			(hide yes)
			(effects
				(font
					(size 1.27 1.27)
				)
			)
		)
		(property "Value" ""
			(at 0 0 180)
			(layer "F.Fab")
			(effects
				(font
					(size 1.27 1.27)
				)
			)
		)
		(duplicate_pad_numbers_are_jumpers no)
		(fp_line
			(start 0.7874 0.4064)
			(end -0.7874 0.4064)
			(stroke
				(width 0.1524)
				(type default)
			)
			(layer "F.SilkS")
		)
		(fp_line
			(start 0.7874 -0.4064)
			(end 0.7874 0.4064)
			(stroke
				(width 0.1524)
				(type default)
			)
			(layer "F.SilkS")
		)
		(fp_line
			(start -0.7874 0.4064)
			(end -0.7874 -0.4064)
			(stroke
				(width 0.1524)
				(type default)
			)
			(layer "F.SilkS")
		)
		(fp_line
			(start -0.7874 -0.4064)
			(end 0.7874 -0.4064)
			(stroke
				(width 0.1524)
				(type default)
			)
			(layer "F.SilkS")
		)
		(fp_line
			(start 0.67945 0.3048)
			(end 0.120396 0.3048)
			(stroke
				(width 0.1)
				(type default)
			)
			(layer "F.Fab")
		)
		(fp_line
			(start 0.67945 -0.3048)
			(end 0.67945 0.3048)
			(stroke
				(width 0.1)
				(type default)
			)
			(layer "F.Fab")
		)
		(fp_line
			(start 0.12065 -0.2794)
			(end 0.12065 -0.3048)
			(stroke
				(width 0.1)
				(type default)
			)
			(layer "F.Fab")
		)
		(fp_line
			(start 0.12065 -0.3048)
			(end 0.67945 -0.3048)
			(stroke
				(width 0.1)
				(type default)
			)
			(layer "F.Fab")
		)
		(fp_line
			(start 0.120396 0.3048)
			(end 0.120396 0.2794)
			(stroke
				(width 0.1)
				(type default)
			)
			(layer "F.Fab")
		)
		(fp_line
			(start 0.120396 0.2794)
			(end -0.12065 0.2794)
			(stroke
				(width 0.1)
				(type default)
			)
			(layer "F.Fab")
		)
		(fp_line
			(start -0.12065 0.3048)
			(end -0.67945 0.3048)
			(stroke
				(width 0.1)
				(type default)
			)
			(layer "F.Fab")
		)
		(fp_line
			(start -0.12065 0.2794)
			(end -0.12065 0.3048)
			(stroke
				(width 0.1)
				(type default)
			)
			(layer "F.Fab")
		)
		(fp_line
			(start -0.12065 -0.2794)
			(end 0.12065 -0.2794)
			(stroke
				(width 0.1)
				(type default)
			)
			(layer "F.Fab")
		)
		(fp_line
			(start -0.12065 -0.305054)
			(end -0.12065 -0.2794)
			(stroke
				(width 0.1)
				(type default)
			)
			(layer "F.Fab")
		)
		(fp_line
			(start -0.67945 0.3048)
			(end -0.67945 -0.305054)
			(stroke
				(width 0.1)
				(type default)
			)
			(layer "F.Fab")
		)
		(fp_line
			(start -0.67945 -0.305054)
			(end -0.12065 -0.305054)
			(stroke
				(width 0.1)
				(type default)
			)
			(layer "F.Fab")
		)
		(pad "1" smd circle
			(at -0.40005 0 180)
			(size 0 0)
			(layers "F.Cu" "F.Mask" "F.Paste")
			(net "HSC_VDD_R")
		)
		(pad "2" smd circle
			(at 0.40005 0 180)
			(size 0 0)
			(layers "F.Cu" "F.Mask" "F.Paste")
			(net "HSC_VDD")
		)
	)
	(footprint ""
		(layer "F.Cu")
		(at 146.939 -121.793)
		(property "Reference" "R8088"
			(at 0 0 0)
			(layer "F.SilkS")
			(hide yes)
			(effects
				(font
					(size 1.27 1.27)
				)
			)
		)
		(property "Value" ""
			(at 0 0 0)
			(layer "F.Fab")
			(effects
				(font
					(size 1.27 1.27)
				)
			)
		)
		(duplicate_pad_numbers_are_jumpers no)
		(fp_line
			(start -0.7874 -0.4064)
			(end 0.7874 -0.4064)
			(stroke
				(width 0.1524)
				(type default)
			)
			(layer "F.SilkS")
		)
		(fp_line
			(start -0.7874 0.4064)
			(end -0.7874 -0.4064)
			(stroke
				(width 0.1524)
				(type default)
			)
			(layer "F.SilkS")
		)
		(fp_line
			(start 0.7874 -0.4064)
			(end 0.7874 0.4064)
			(stroke
				(width 0.1524)
				(type default)
			)
			(layer "F.SilkS")
		)
		(fp_line
			(start 0.7874 0.4064)
			(end -0.7874 0.4064)
			(stroke
				(width 0.1524)
				(type default)
			)
			(layer "F.SilkS")
		)
		(fp_line
			(start -0.67945 -0.305054)
			(end -0.12065 -0.305054)
			(stroke
				(width 0.1)
				(type default)
			)
			(layer "F.Fab")
		)
		(fp_line
			(start -0.67945 0.3048)
			(end -0.67945 -0.305054)
			(stroke
				(width 0.1)
				(type default)
			)
			(layer "F.Fab")
		)
		(fp_line
			(start -0.12065 -0.305054)
			(end -0.12065 -0.2794)
			(stroke
				(width 0.1)
				(type default)
			)
			(layer "F.Fab")
		)
		(fp_line
			(start -0.12065 -0.2794)
			(end 0.12065 -0.2794)
			(stroke
				(width 0.1)
				(type default)
			)
			(layer "F.Fab")
		)
		(fp_line
			(start -0.12065 0.2794)
			(end -0.12065 0.3048)
			(stroke
				(width 0.1)
				(type default)
			)
			(layer "F.Fab")
		)
		(fp_line
			(start -0.12065 0.3048)
			(end -0.67945 0.3048)
			(stroke
				(width 0.1)
				(type default)
			)
			(layer "F.Fab")
		)
		(fp_line
			(start 0.120396 0.2794)
			(end -0.12065 0.2794)
			(stroke
				(width 0.1)
				(type default)
			)
			(layer "F.Fab")
		)
		(fp_line
			(start 0.120396 0.3048)
			(end 0.120396 0.2794)
			(stroke
				(width 0.1)
				(type default)
			)
			(layer "F.Fab")
		)
		(fp_line
			(start 0.12065 -0.3048)
			(end 0.67945 -0.3048)
			(stroke
				(width 0.1)
				(type default)
			)
			(layer "F.Fab")
		)
		(fp_line
			(start 0.12065 -0.2794)
			(end 0.12065 -0.3048)
			(stroke
				(width 0.1)
				(type default)
			)
			(layer "F.Fab")
		)
		(fp_line
			(start 0.67945 -0.3048)
			(end 0.67945 0.3048)
			(stroke
				(width 0.1)
				(type default)
			)
			(layer "F.Fab")
		)
		(fp_line
			(start 0.67945 0.3048)
			(end 0.120396 0.3048)
			(stroke
				(width 0.1)
				(type default)
			)
			(layer "F.Fab")
		)
		(pad "1" smd circle
			(at -0.40005 0)
			(size 0 0)
			(layers "F.Cu" "F.Mask" "F.Paste")
			(net "P3V3_AUX")
		)
		(pad "2" smd circle
			(at 0.40005 0)
			(size 0 0)
			(layers "F.Cu" "F.Mask" "F.Paste")
			(net "PWRGD_CHAF_CPU1_R1")
		)
	)
	(footprint ""
		(layer "F.Cu")
		(at 304.301398 -431.2539)
		(property "Reference" "R4132"
			(at 0 0 0)
			(layer "F.SilkS")
			(hide yes)
			(effects
				(font
					(size 1.27 1.27)
				)
			)
		)
		(property "Value" ""
			(at 0 0 0)
			(layer "F.Fab")
			(effects
				(font
					(size 1.27 1.27)
				)
			)
		)
		(duplicate_pad_numbers_are_jumpers no)
		(fp_line
			(start -0.7874 -0.4064)
			(end 0.7874 -0.4064)
			(stroke
				(width 0.1524)
				(type default)
			)
			(layer "F.SilkS")
		)
		(fp_line
			(start -0.7874 0.4064)
			(end -0.7874 -0.4064)
			(stroke
				(width 0.1524)
				(type default)
			)
			(layer "F.SilkS")
		)
		(fp_line
			(start 0.7874 -0.4064)
			(end 0.7874 0.4064)
			(stroke
				(width 0.1524)
				(type default)
			)
			(layer "F.SilkS")
		)
		(fp_line
			(start 0.7874 0.4064)
			(end -0.7874 0.4064)
			(stroke
				(width 0.1524)
				(type default)
			)
			(layer "F.SilkS")
		)
		(fp_line
			(start -0.67945 -0.305054)
			(end -0.12065 -0.305054)
			(stroke
				(width 0.1)
				(type default)
			)
			(layer "F.Fab")
		)
		(fp_line
			(start -0.67945 0.3048)
			(end -0.67945 -0.305054)
			(stroke
				(width 0.1)
				(type default)
			)
			(layer "F.Fab")
		)
		(fp_line
			(start -0.12065 -0.305054)
			(end -0.12065 -0.2794)
			(stroke
				(width 0.1)
				(type default)
			)
			(layer "F.Fab")
		)
		(fp_line
			(start -0.12065 -0.2794)
			(end 0.12065 -0.2794)
			(stroke
				(width 0.1)
				(type default)
			)
			(layer "F.Fab")
		)
		(fp_line
			(start -0.12065 0.2794)
			(end -0.12065 0.3048)
			(stroke
				(width 0.1)
				(type default)
			)
			(layer "F.Fab")
		)
		(fp_line
			(start -0.12065 0.3048)
			(end -0.67945 0.3048)
			(stroke
				(width 0.1)
				(type default)
			)
			(layer "F.Fab")
		)
		(fp_line
			(start 0.120396 0.2794)
			(end -0.12065 0.2794)
			(stroke
				(width 0.1)
				(type default)
			)
			(layer "F.Fab")
		)
		(fp_line
			(start 0.120396 0.3048)
			(end 0.120396 0.2794)
			(stroke
				(width 0.1)
				(type default)
			)
			(layer "F.Fab")
		)
		(fp_line
			(start 0.12065 -0.3048)
			(end 0.67945 -0.3048)
			(stroke
				(width 0.1)
				(type default)
			)
			(layer "F.Fab")
		)
		(fp_line
			(start 0.12065 -0.2794)
			(end 0.12065 -0.3048)
			(stroke
				(width 0.1)
				(type default)
			)
			(layer "F.Fab")
		)
		(fp_line
			(start 0.67945 -0.3048)
			(end 0.67945 0.3048)
			(stroke
				(width 0.1)
				(type default)
			)
			(layer "F.Fab")
		)
		(fp_line
			(start 0.67945 0.3048)
			(end 0.120396 0.3048)
			(stroke
				(width 0.1)
				(type default)
			)
			(layer "F.Fab")
		)
		(pad "1" smd circle
			(at -0.40005 0)
			(size 0 0)
			(layers "F.Cu" "F.Mask" "F.Paste")
			(net "GPU_3V3IO_RSVD3_FFU")
		)
		(pad "2" smd circle
			(at 0.40005 0)
			(size 0 0)
			(layers "F.Cu" "F.Mask" "F.Paste")
			(net "GND")
		)
	)
	(footprint ""
		(layer "F.Cu")
		(at 38.443662 -424.202098)
		(property "Reference" "R3291"
			(at 0 0 0)
			(layer "F.SilkS")
			(hide yes)
			(effects
				(font
					(size 1.27 1.27)
				)
			)
		)
		(property "Value" ""
			(at 0 0 0)
			(layer "F.Fab")
			(effects
				(font
					(size 1.27 1.27)
				)
			)
		)
		(duplicate_pad_numbers_are_jumpers no)
		(fp_line
			(start -0.7874 -0.4064)
			(end 0.7874 -0.4064)
			(stroke
				(width 0.1524)
				(type default)
			)
			(layer "F.SilkS")
		)
		(fp_line
			(start -0.7874 0.4064)
			(end -0.7874 -0.4064)
			(stroke
				(width 0.1524)
				(type default)
			)
			(layer "F.SilkS")
		)
		(fp_line
			(start 0.7874 -0.4064)
			(end 0.7874 0.4064)
			(stroke
				(width 0.1524)
				(type default)
			)
			(layer "F.SilkS")
		)
		(fp_line
			(start 0.7874 0.4064)
			(end -0.7874 0.4064)
			(stroke
				(width 0.1524)
				(type default)
			)
			(layer "F.SilkS")
		)
		(fp_line
			(start -0.67945 -0.305054)
			(end -0.12065 -0.305054)
			(stroke
				(width 0.1)
				(type default)
			)
			(layer "F.Fab")
		)
		(fp_line
			(start -0.67945 0.3048)
			(end -0.67945 -0.305054)
			(stroke
				(width 0.1)
				(type default)
			)
			(layer "F.Fab")
		)
		(fp_line
			(start -0.12065 -0.305054)
			(end -0.12065 -0.2794)
			(stroke
				(width 0.1)
				(type default)
			)
			(layer "F.Fab")
		)
		(fp_line
			(start -0.12065 -0.2794)
			(end 0.12065 -0.2794)
			(stroke
				(width 0.1)
				(type default)
			)
			(layer "F.Fab")
		)
		(fp_line
			(start -0.12065 0.2794)
			(end -0.12065 0.3048)
			(stroke
				(width 0.1)
				(type default)
			)
			(layer "F.Fab")
		)
		(fp_line
			(start -0.12065 0.3048)
			(end -0.67945 0.3048)
			(stroke
				(width 0.1)
				(type default)
			)
			(layer "F.Fab")
		)
		(fp_line
			(start 0.120396 0.2794)
			(end -0.12065 0.2794)
			(stroke
				(width 0.1)
				(type default)
			)
			(layer "F.Fab")
		)
		(fp_line
			(start 0.120396 0.3048)
			(end 0.120396 0.2794)
			(stroke
				(width 0.1)
				(type default)
			)
			(layer "F.Fab")
		)
		(fp_line
			(start 0.12065 -0.3048)
			(end 0.67945 -0.3048)
			(stroke
				(width 0.1)
				(type default)
			)
			(layer "F.Fab")
		)
		(fp_line
			(start 0.12065 -0.2794)
			(end 0.12065 -0.3048)
			(stroke
				(width 0.1)
				(type default)
			)
			(layer "F.Fab")
		)
		(fp_line
			(start 0.67945 -0.3048)
			(end 0.67945 0.3048)
			(stroke
				(width 0.1)
				(type default)
			)
			(layer "F.Fab")
		)
		(fp_line
			(start 0.67945 0.3048)
			(end 0.120396 0.3048)
			(stroke
				(width 0.1)
				(type default)
			)
			(layer "F.Fab")
		)
		(pad "1" smd circle
			(at -0.40005 0)
			(size 0 0)
			(layers "F.Cu" "F.Mask" "F.Paste")
			(net "PU_TEST")
		)
		(pad "2" smd circle
			(at 0.40005 0)
			(size 0 0)
			(layers "F.Cu" "F.Mask" "F.Paste")
			(net "GND")
		)
	)
)
